(kicad_pcb
	(version 20260206)
	(generator "pcbnew")
	(generator_version "10.0")
	(general
		(thickness 1.6)
		(legacy_teardrops no)
	)
	(paper "A4")
	(title_block
		(title "v1-chassis-manager — T6M_CM_d_v01_1031_1645.brd")
		(comment 1 "Open CloudServer (Microsoft) / footprints 1826-1834 of 2512")
	)
	(layers
		(0 "F.Cu" signal "TOP")
		(4 "In1.Cu" signal "GND1")
		(6 "In2.Cu" signal "IN1")
		(8 "In3.Cu" signal "VCC1")
		(10 "In4.Cu" signal "VCC2")
		(12 "In5.Cu" signal "GND2")
		(14 "In6.Cu" signal "IN2")
		(16 "In7.Cu" signal "IN3")
		(18 "In8.Cu" signal "GND3")
		(2 "B.Cu" signal "BOTTOM")
		(9 "F.Adhes" user "F.Adhesive")
		(11 "B.Adhes" user "B.Adhesive")
		(13 "F.Paste" user "Package Geometry/Pastemask Top")
		(15 "B.Paste" user "Package Geometry/Pastemask Bottom")
		(5 "F.SilkS" user "Ref Des/Silkscreen Top")
		(7 "B.SilkS" user "Ref Des/Silkscreen Bottom")
		(1 "F.Mask" user "Board Geometry/Soldermask Top")
		(3 "B.Mask" user "Board Geometry/Soldermask Bottom")
		(17 "Dwgs.User" user "User.Drawings")
		(19 "Cmts.User" user "User.Comments")
		(21 "Eco1.User" user "User.Eco1")
		(23 "Eco2.User" user "User.Eco2")
		(25 "Edge.Cuts" user "Board Geometry/Outline")
		(27 "Margin" user)
		(31 "F.CrtYd" user "Package Geometry/Place Bound Top")
		(29 "B.CrtYd" user "Package Geometry/Place Bound Bottom")
		(35 "F.Fab" user "Ref Des/Assembly Top")
		(33 "B.Fab" user "Ref Des/Assembly Bottom")
	)
	(footprint ""
		(layer "B.Cu")
		(at 157.33776 -184.951624 90)
		(property "Reference" "R828"
			(at 4.230624 -1.943608 270)
			(unlocked yes)
			(layer "B.SilkS")
			(effects
				(font
					(size 0.7874 0.5842)
					(thickness 0.1524)
				)
				(justify left mirror)
			)
		)
		(property "Value" ""
			(at 0 0 90)
			(layer "B.Fab")
			(effects
				(font
					(size 1.27 1.27)
				)
				(justify mirror)
			)
		)
		(duplicate_pad_numbers_are_jumpers no)
		(fp_line
			(start 0.7874 -0.4064)
			(end -0.7874 -0.4064)
			(stroke
				(width 0.1524)
				(type default)
			)
			(layer "B.SilkS")
		)
		(fp_line
			(start -0.7874 -0.4064)
			(end -0.7874 0.4064)
			(stroke
				(width 0.1524)
				(type default)
			)
			(layer "B.SilkS")
		)
		(fp_line
			(start 0.7874 0.4064)
			(end 0.7874 -0.4064)
			(stroke
				(width 0.1524)
				(type default)
			)
			(layer "B.SilkS")
		)
		(fp_line
			(start -0.7874 0.4064)
			(end 0.7874 0.4064)
			(stroke
				(width 0.1524)
				(type default)
			)
			(layer "B.SilkS")
		)
		(fp_poly
			(pts
				(xy 0.508 0.2794) (xy 0.508 0.2286) (xy 0.635 0.2286) (xy 0.635 -0.254) (xy 0.5334 -0.254) (xy 0.5334 -0.2794)
				(xy -0.5334 -0.2794) (xy -0.5334 -0.254) (xy -0.635 -0.254) (xy -0.635 0.254) (xy -0.5334 0.254)
				(xy -0.5334 0.2794)
			)
			(stroke
				(width 0)
				(type default)
			)
			(fill no)
			(layer "B.CrtYd")
		)
		(pad "1" smd rect
			(at -0.40005 0 270)
			(size 0.4572 0.508)
			(layers "B.Cu" "B.Mask" "B.Paste")
			(net "I2C_PSU3_SCL")
		)
		(pad "2" smd rect
			(at 0.40005 0 270)
			(size 0.4572 0.508)
			(layers "B.Cu" "B.Mask" "B.Paste")
			(net "I2C_PSU3_R_SCL")
		)
	)
	(footprint ""
		(layer "B.Cu")
		(at 57.840372 -71.370698)
		(property "Reference" "PJ7"
			(at -14.298422 34.722054 270)
			(unlocked yes)
			(layer "B.SilkS")
			(effects
				(font
					(size 0.7874 0.5842)
					(thickness 0.1524)
				)
				(justify left mirror)
			)
		)
		(property "Value" ""
			(at 0 0 0)
			(layer "B.Fab")
			(effects
				(font
					(size 1.27 1.27)
				)
				(justify mirror)
			)
		)
		(duplicate_pad_numbers_are_jumpers no)
		(fp_poly
			(pts
				(xy -0.2794 0.907796) (xy -0.254 0.907796) (xy -0.254 1.0414) (xy 0.254 1.0414) (xy 0.254 1.034796)
				(xy 0.254 0.933196) (xy 0.2794 0.933196) (xy 0.2794 -0.133604) (xy 0.254 -0.133604) (xy 0.254 -0.235204)
				(xy -0.254 -0.235204) (xy -0.254 -0.133604) (xy -0.2794 -0.133604)
			)
			(stroke
				(width 0)
				(type default)
			)
			(fill no)
			(layer "B.CrtYd")
		)
		(pad "1" smd custom
			(at 0 -0.000254 180)
			(size 0.127 0.127)
			(layers "B.Cu" "B.Mask" "B.Paste")
			(net "GND")
			(options
				(clearance outline)
				(anchor circle)
			)
			(primitives
				(gr_poly
					(pts
						(xy -0.127 -0.508) (xy -0.127 0.0508) (xy -0.254 0.0508) (xy -0.254 0.508) (xy 0.254 0.508) (xy 0.254 0.0508)
						(xy 0.127 0.0508) (xy 0.127 -0.508)
					)
					(width 0)
					(fill yes)
				)
			)
		)
		(pad "2" smd rect
			(at 0 0.799846 90)
			(size 0.4572 0.508)
			(layers "B.Cu" "B.Mask" "B.Paste")
			(net "VSENSE_P1V05_NODE1_N")
		)
		(zone
			(layer "B.Cu")
			(hatch none 0.5)
			(connect_pads
				(clearance 0)
			)
			(min_thickness 0.25)
			(keepout
				(tracks allowed)
				(vias not_allowed)
				(pads allowed)
				(copperpour not_allowed)
				(footprints allowed)
			)
			(placement
				(enabled no)
				(sheetname "")
			)
			(fill
				(thermal_gap 0.5)
				(thermal_bridge_width 0.5)
				(island_removal_mode 0)
			)
			(polygon
				(pts
					(xy 58.145172 -70.285102) (xy 57.535572 -70.285102) (xy 57.535572 -71.656702) (xy 58.145172 -71.656702)
				)
			)
		)
	)
	(footprint ""
		(layer "B.Cu")
		(at 101.858572 -181.928516)
		(property "Reference" "R1060"
			(at 4.933188 -0.15875 0)
			(unlocked yes)
			(layer "B.SilkS")
			(effects
				(font
					(size 0.7874 0.5842)
					(thickness 0.1524)
				)
				(justify left mirror)
			)
		)
		(property "Value" ""
			(at 0 0 0)
			(layer "B.Fab")
			(effects
				(font
					(size 1.27 1.27)
				)
				(justify mirror)
			)
		)
		(duplicate_pad_numbers_are_jumpers no)
		(fp_line
			(start -0.7874 -0.4064)
			(end -0.7874 0.4064)
			(stroke
				(width 0.1524)
				(type default)
			)
			(layer "B.SilkS")
		)
		(fp_line
			(start -0.7874 0.4064)
			(end 0.7874 0.4064)
			(stroke
				(width 0.1524)
				(type default)
			)
			(layer "B.SilkS")
		)
		(fp_line
			(start 0.7874 -0.4064)
			(end -0.7874 -0.4064)
			(stroke
				(width 0.1524)
				(type default)
			)
			(layer "B.SilkS")
		)
		(fp_line
			(start 0.7874 0.4064)
			(end 0.7874 -0.4064)
			(stroke
				(width 0.1524)
				(type default)
			)
			(layer "B.SilkS")
		)
		(fp_poly
			(pts
				(xy 0.508 0.2794) (xy 0.508 0.2286) (xy 0.635 0.2286) (xy 0.635 -0.254) (xy 0.5334 -0.254) (xy 0.5334 -0.2794)
				(xy -0.5334 -0.2794) (xy -0.5334 -0.254) (xy -0.635 -0.254) (xy -0.635 0.254) (xy -0.5334 0.254)
				(xy -0.5334 0.2794)
			)
			(stroke
				(width 0)
				(type default)
			)
			(fill no)
			(layer "B.CrtYd")
		)
		(pad "1" smd rect
			(at -0.40005 0 180)
			(size 0.4572 0.508)
			(layers "B.Cu" "B.Mask" "B.Paste")
			(net "POWER_SW3_PWR_CTR_N")
		)
		(pad "2" smd rect
			(at 0.40005 0 180)
			(size 0.4572 0.508)
			(layers "B.Cu" "B.Mask" "B.Paste")
			(net "P3V3_STB_NODE1")
		)
	)
	(footprint ""
		(layer "B.Cu")
		(at 37.606732 -94.40037 90)
		(property "Reference" "R125"
			(at -4.703318 -4.651502 270)
			(unlocked yes)
			(layer "B.SilkS")
			(effects
				(font
					(size 0.7874 0.5842)
					(thickness 0.1524)
				)
				(justify left mirror)
			)
		)
		(property "Value" ""
			(at 0 0 90)
			(layer "B.Fab")
			(effects
				(font
					(size 1.27 1.27)
				)
				(justify mirror)
			)
		)
		(duplicate_pad_numbers_are_jumpers no)
		(fp_line
			(start 0.7874 -0.4064)
			(end -0.7874 -0.4064)
			(stroke
				(width 0.1524)
				(type default)
			)
			(layer "B.SilkS")
		)
		(fp_line
			(start -0.7874 -0.4064)
			(end -0.7874 0.4064)
			(stroke
				(width 0.1524)
				(type default)
			)
			(layer "B.SilkS")
		)
		(fp_line
			(start 0.7874 0.4064)
			(end 0.7874 -0.4064)
			(stroke
				(width 0.1524)
				(type default)
			)
			(layer "B.SilkS")
		)
		(fp_line
			(start -0.7874 0.4064)
			(end 0.7874 0.4064)
			(stroke
				(width 0.1524)
				(type default)
			)
			(layer "B.SilkS")
		)
		(fp_poly
			(pts
				(xy 0.508 0.2794) (xy 0.508 0.2286) (xy 0.635 0.2286) (xy 0.635 -0.254) (xy 0.5334 -0.254) (xy 0.5334 -0.2794)
				(xy -0.5334 -0.2794) (xy -0.5334 -0.254) (xy -0.635 -0.254) (xy -0.635 0.254) (xy -0.5334 0.254)
				(xy -0.5334 0.2794)
			)
			(stroke
				(width 0)
				(type default)
			)
			(fill no)
			(layer "B.CrtYd")
		)
		(pad "1" smd rect
			(at -0.40005 0 270)
			(size 0.4572 0.508)
			(layers "B.Cu" "B.Mask" "B.Paste")
			(net "SMB_CPU_NODE1_MEM_ICS_CLK_R")
		)
		(pad "2" smd rect
			(at 0.40005 0 270)
			(size 0.4572 0.508)
			(layers "B.Cu" "B.Mask" "B.Paste")
			(net "SMB_MUX_CPU_ICS_NODE1_CLK")
		)
	)
	(footprint ""
		(layer "B.Cu")
		(at 134.756652 -135.87095 90)
		(property "Reference" "C892"
			(at -5.07365 0.33147 270)
			(unlocked yes)
			(layer "B.SilkS")
			(effects
				(font
					(size 0.7874 0.5842)
					(thickness 0.1524)
				)
				(justify left mirror)
			)
		)
		(property "Value" ""
			(at 0 0 90)
			(layer "B.Fab")
			(effects
				(font
					(size 1.27 1.27)
				)
				(justify mirror)
			)
		)
		(duplicate_pad_numbers_are_jumpers no)
		(fp_line
			(start 0.7874 -0.4064)
			(end -0.7874 -0.4064)
			(stroke
				(width 0.1524)
				(type default)
			)
			(layer "B.SilkS")
		)
		(fp_line
			(start -0.7874 -0.4064)
			(end -0.7874 0.4064)
			(stroke
				(width 0.1524)
				(type default)
			)
			(layer "B.SilkS")
		)
		(fp_line
			(start 0 0.381)
			(end 0 -0.381)
			(stroke
				(width 0.1524)
				(type default)
			)
			(layer "B.SilkS")
		)
		(fp_line
			(start 0.7874 0.4064)
			(end 0.7874 -0.4064)
			(stroke
				(width 0.1524)
				(type default)
			)
			(layer "B.SilkS")
		)
		(fp_line
			(start -0.7874 0.4064)
			(end 0.7874 0.4064)
			(stroke
				(width 0.1524)
				(type default)
			)
			(layer "B.SilkS")
		)
		(fp_poly
			(pts
				(xy 0.5334 0.254) (xy 0.635 0.254) (xy 0.635 0.2286) (xy 0.635 -0.254) (xy 0.5334 -0.254) (xy 0.5334 -0.2794)
				(xy -0.5334 -0.2794) (xy -0.5334 -0.254) (xy -0.635 -0.254) (xy -0.635 0.254) (xy -0.5334 0.254)
				(xy -0.5334 0.2794) (xy 0.508 0.2794) (xy 0.5334 0.2794)
			)
			(stroke
				(width 0)
				(type default)
			)
			(fill no)
			(layer "B.CrtYd")
		)
		(pad "1" smd rect
			(at -0.40005 0 270)
			(size 0.4572 0.508)
			(layers "B.Cu" "B.Mask" "B.Paste")
			(net "P1V538_BMC_NODE1")
		)
		(pad "2" smd rect
			(at 0.40005 0 270)
			(size 0.4572 0.508)
			(layers "B.Cu" "B.Mask" "B.Paste")
			(net "GND")
		)
	)
	(footprint ""
		(layer "B.Cu")
		(at 91.47302 -71.200518)
		(property "Reference" "R172"
			(at 4.07797 0.606044 0)
			(unlocked yes)
			(layer "B.SilkS")
			(effects
				(font
					(size 0.7874 0.5842)
					(thickness 0.1524)
				)
				(justify left mirror)
			)
		)
		(property "Value" ""
			(at 0 0 0)
			(layer "B.Fab")
			(effects
				(font
					(size 1.27 1.27)
				)
				(justify mirror)
			)
		)
		(duplicate_pad_numbers_are_jumpers no)
		(fp_line
			(start -0.7874 -0.4064)
			(end -0.7874 0.4064)
			(stroke
				(width 0.1524)
				(type default)
			)
			(layer "B.SilkS")
		)
		(fp_line
			(start -0.7874 0.4064)
			(end 0.7874 0.4064)
			(stroke
				(width 0.1524)
				(type default)
			)
			(layer "B.SilkS")
		)
		(fp_line
			(start 0.7874 -0.4064)
			(end -0.7874 -0.4064)
			(stroke
				(width 0.1524)
				(type default)
			)
			(layer "B.SilkS")
		)
		(fp_line
			(start 0.7874 0.4064)
			(end 0.7874 -0.4064)
			(stroke
				(width 0.1524)
				(type default)
			)
			(layer "B.SilkS")
		)
		(fp_poly
			(pts
				(xy 0.508 0.2794) (xy 0.508 0.2286) (xy 0.635 0.2286) (xy 0.635 -0.254) (xy 0.5334 -0.254) (xy 0.5334 -0.2794)
				(xy -0.5334 -0.2794) (xy -0.5334 -0.254) (xy -0.635 -0.254) (xy -0.635 0.254) (xy -0.5334 0.254)
				(xy -0.5334 0.2794)
			)
			(stroke
				(width 0)
				(type default)
			)
			(fill no)
			(layer "B.CrtYd")
		)
		(pad "1" smd rect
			(at -0.40005 0 180)
			(size 0.4572 0.508)
			(layers "B.Cu" "B.Mask" "B.Paste")
			(net "PD_CPU_NODE1_PUNIT_ST_ADDR1")
		)
		(pad "2" smd rect
			(at 0.40005 0 180)
			(size 0.4572 0.508)
			(layers "B.Cu" "B.Mask" "B.Paste")
			(net "P1V05_SUS_NODE1")
		)
	)
	(footprint ""
		(layer "B.Cu")
		(at 167.000428 -198.83247)
		(property "Reference" "TP11"
			(at 0 0 0)
			(layer "B.SilkS")
			(hide yes)
			(effects
				(font
					(size 1.27 1.27)
				)
				(justify mirror)
			)
		)
		(property "Value" ""
			(at 0 0 0)
			(layer "B.Fab")
			(effects
				(font
					(size 1.27 1.27)
				)
				(justify mirror)
			)
		)
		(duplicate_pad_numbers_are_jumpers no)
		(fp_poly
			(pts
				(arc
					(start 0.381 0)
					(mid -0.381 0)
					(end 0.381 0)
				)
			)
			(stroke
				(width 0)
				(type default)
			)
			(fill no)
			(layer "B.CrtYd")
		)
		(pad "1" smd circle
			(at 0 0 180)
			(size 0.762 0.762)
			(layers "B.Cu" "B.Mask" "B.Paste")
			(net "UART_DSR_RP6_L_N")
		)
	)
	(footprint ""
		(layer "B.Cu")
		(at 116.44376 -177.204624 -90)
		(property "Reference" "U64"
			(at 30.083506 24.9682 0)
			(unlocked yes)
			(layer "B.SilkS")
			(effects
				(font
					(size 0.7874 0.5842)
					(thickness 0.1524)
				)
				(justify left mirror)
			)
		)
		(property "Value" ""
			(at 0 0 90)
			(layer "B.Fab")
			(effects
				(font
					(size 1.27 1.27)
				)
				(justify mirror)
			)
		)
		(duplicate_pad_numbers_are_jumpers no)
		(fp_line
			(start -3.9624 2.0066)
			(end 3.9624 2.0066)
			(stroke
				(width 0.1524)
				(type default)
			)
			(layer "B.SilkS")
		)
		(fp_line
			(start 3.9624 2.0066)
			(end 3.9624 0.5842)
			(stroke
				(width 0.1524)
				(type default)
			)
			(layer "B.SilkS")
		)
		(fp_line
			(start 3.9624 0.5842)
			(end 3.3782 0)
			(stroke
				(width 0.1524)
				(type default)
			)
			(layer "B.SilkS")
		)
		(fp_line
			(start 3.3782 0)
			(end 3.9624 -0.5842)
			(stroke
				(width 0.1524)
				(type default)
			)
			(layer "B.SilkS")
		)
		(fp_line
			(start 3.9624 -0.5842)
			(end 3.9624 -2.0066)
			(stroke
				(width 0.1524)
				(type default)
			)
			(layer "B.SilkS")
		)
		(fp_line
			(start -3.9624 -2.0066)
			(end -3.9624 2.0066)
			(stroke
				(width 0.1524)
				(type default)
			)
			(layer "B.SilkS")
		)
		(fp_line
			(start 3.9624 -2.0066)
			(end -3.9624 -2.0066)
			(stroke
				(width 0.1524)
				(type default)
			)
			(layer "B.SilkS")
		)
		(fp_circle
			(center 3.429 1.524)
			(end 3.429 1.27)
			(stroke
				(width 0.1524)
				(type default)
			)
			(fill no)
			(layer "B.SilkS")
		)
		(fp_poly
			(pts
				(xy 3.962654 3.6703) (xy 3.974846 -3.6703) (xy -3.9624 -3.6703) (xy -3.9624 3.6703)
			)
			(stroke
				(width 0)
				(type default)
			)
			(fill no)
			(layer "B.CrtYd")
		)
		(pad "1" smd rect
			(at 3.57505 2.921 90)
			(size 0.3556 1.4986)
			(layers "B.Cu" "B.Mask" "B.Paste")
			(net "N21699571")
		)
		(pad "2" smd rect
			(at 2.925064 2.921 90)
			(size 0.3556 1.4986)
			(layers "B.Cu" "B.Mask" "B.Paste")
			(net "N21699716")
		)
		(pad "3" smd rect
			(at 2.275078 2.921 90)
			(size 0.3556 1.4986)
			(layers "B.Cu" "B.Mask" "B.Paste")
			(net "N21699716")
		)
		(pad "4" smd rect
			(at 1.625092 2.921 90)
			(size 0.3556 1.4986)
			(layers "B.Cu" "B.Mask" "B.Paste")
			(net "T5_NODE1_EN")
		)
		(pad "5" smd rect
			(at 0.975106 2.921 90)
			(size 0.3556 1.4986)
			(layers "B.Cu" "B.Mask" "B.Paste")
			(net "T5_NODE2_EN")
		)
		(pad "6" smd rect
			(at 0.32512 2.921 90)
			(size 0.3556 1.4986)
			(layers "B.Cu" "B.Mask" "B.Paste")
			(net "T5_NODE3_EN")
		)
		(pad "7" smd rect
			(at -0.32512 2.921 90)
			(size 0.3556 1.4986)
			(layers "B.Cu" "B.Mask" "B.Paste")
			(net "T5_NODE4_EN")
		)
		(pad "8" smd rect
			(at -0.975106 2.921 90)
			(size 0.3556 1.4986)
			(layers "B.Cu" "B.Mask" "B.Paste")
			(net "T6_NODE1_EN")
		)
		(pad "9" smd rect
			(at -1.625092 2.921 90)
			(size 0.3556 1.4986)
			(layers "B.Cu" "B.Mask" "B.Paste")
			(net "T6_NODE2_EN")
		)
		(pad "10" smd rect
			(at -2.275078 2.921 90)
			(size 0.3556 1.4986)
			(layers "B.Cu" "B.Mask" "B.Paste")
			(net "T6_NODE3_EN")
		)
		(pad "11" smd rect
			(at -2.925064 2.921 90)
			(size 0.3556 1.4986)
			(layers "B.Cu" "B.Mask" "B.Paste")
			(net "T6_NODE4_EN")
		)
		(pad "12" smd rect
			(at -3.57505 2.921 90)
			(size 0.3556 1.4986)
			(layers "B.Cu" "B.Mask" "B.Paste")
			(net "GND")
		)
		(pad "13" smd rect
			(at -3.57505 -2.921 90)
			(size 0.3556 1.4986)
			(layers "B.Cu" "B.Mask" "B.Paste")
			(net "T7_NODE1_EN")
		)
		(pad "14" smd rect
			(at -2.925064 -2.921 90)
			(size 0.3556 1.4986)
			(layers "B.Cu" "B.Mask" "B.Paste")
			(net "T7_NODE2_EN")
		)
		(pad "15" smd rect
			(at -2.275078 -2.921 90)
			(size 0.3556 1.4986)
			(layers "B.Cu" "B.Mask" "B.Paste")
			(net "T7_NODE3_EN")
		)
		(pad "16" smd rect
			(at -1.625092 -2.921 90)
			(size 0.3556 1.4986)
			(layers "B.Cu" "B.Mask" "B.Paste")
			(net "T7_NODE4_EN")
		)
		(pad "17" smd rect
			(at -0.975106 -2.921 90)
			(size 0.3556 1.4986)
			(layers "B.Cu" "B.Mask" "B.Paste")
			(net "T8_NODE1_EN")
		)
		(pad "18" smd rect
			(at -0.32512 -2.921 90)
			(size 0.3556 1.4986)
			(layers "B.Cu" "B.Mask" "B.Paste")
			(net "T8_NODE2_EN")
		)
		(pad "19" smd rect
			(at 0.32512 -2.921 90)
			(size 0.3556 1.4986)
			(layers "B.Cu" "B.Mask" "B.Paste")
			(net "T8_NODE3_EN")
		)
		(pad "20" smd rect
			(at 0.975106 -2.921 90)
			(size 0.3556 1.4986)
			(layers "B.Cu" "B.Mask" "B.Paste")
			(net "T8_NODE4_EN")
		)
		(pad "21" smd rect
			(at 1.625092 -2.921 90)
			(size 0.3556 1.4986)
			(layers "B.Cu" "B.Mask" "B.Paste")
			(net "N21699372")
		)
		(pad "22" smd rect
			(at 2.275078 -2.921 90)
			(size 0.3556 1.4986)
			(layers "B.Cu" "B.Mask" "B.Paste")
			(net "I2C_COM3_SCL")
		)
		(pad "23" smd rect
			(at 2.925064 -2.921 90)
			(size 0.3556 1.4986)
			(layers "B.Cu" "B.Mask" "B.Paste")
			(net "I2C_COM3_SDA")
		)
		(pad "24" smd rect
			(at 3.57505 -2.921 90)
			(size 0.3556 1.4986)
			(layers "B.Cu" "B.Mask" "B.Paste")
			(net "P3V3_NODE1")
		)
	)
	(footprint ""
		(layer "B.Cu")
		(at 77.396086 -126.454662)
		(property "Reference" "C284"
			(at 3.903472 0.129032 0)
			(unlocked yes)
			(layer "B.SilkS")
			(effects
				(font
					(size 0.7874 0.5842)
					(thickness 0.1524)
				)
				(justify left mirror)
			)
		)
		(property "Value" ""
			(at 0 0 0)
			(layer "B.Fab")
			(effects
				(font
					(size 1.27 1.27)
				)
				(justify mirror)
			)
		)
		(duplicate_pad_numbers_are_jumpers no)
		(fp_line
			(start -0.7874 -0.4064)
			(end -0.7874 0.4064)
			(stroke
				(width 0.1524)
				(type default)
			)
			(layer "B.SilkS")
		)
		(fp_line
			(start -0.7874 0.4064)
			(end 0.7874 0.4064)
			(stroke
				(width 0.1524)
				(type default)
			)
			(layer "B.SilkS")
		)
		(fp_line
			(start 0 0.381)
			(end 0 -0.381)
			(stroke
				(width 0.1524)
				(type default)
			)
			(layer "B.SilkS")
		)
		(fp_line
			(start 0.7874 -0.4064)
			(end -0.7874 -0.4064)
			(stroke
				(width 0.1524)
				(type default)
			)
			(layer "B.SilkS")
		)
		(fp_line
			(start 0.7874 0.4064)
			(end 0.7874 -0.4064)
			(stroke
				(width 0.1524)
				(type default)
			)
			(layer "B.SilkS")
		)
		(fp_poly
			(pts
				(xy 0.5334 0.254) (xy 0.635 0.254) (xy 0.635 0.2286) (xy 0.635 -0.254) (xy 0.5334 -0.254) (xy 0.5334 -0.2794)
				(xy -0.5334 -0.2794) (xy -0.5334 -0.254) (xy -0.635 -0.254) (xy -0.635 0.254) (xy -0.5334 0.254)
				(xy -0.5334 0.2794) (xy 0.508 0.2794) (xy 0.5334 0.2794)
			)
			(stroke
				(width 0)
				(type default)
			)
			(fill no)
			(layer "B.CrtYd")
		)
		(pad "1" smd rect
			(at -0.40005 0 180)
			(size 0.4572 0.508)
			(layers "B.Cu" "B.Mask" "B.Paste")
			(net "BMC_NODE1_VCC_1V8_PCIEA")
		)
		(pad "2" smd rect
			(at 0.40005 0 180)
			(size 0.4572 0.508)
			(layers "B.Cu" "B.Mask" "B.Paste")
			(net "GND")
		)
	)
)
